FILE_TYPE = MACRO_DRAWING;
SET COLOR_WIRE YELLOW;
SET COLOR_PROP ORANGE;
SET COLOR_DOT WHITE;
SET COLOR_ARC YELLOW;
SET COLOR_BODY GREEN;
SET COLOR_NOTE PURPLE;
SET PROP_DISPLAY VALUE;
SET PAGE_NUMBER P310;
FORCEADD UNIVERSAL_GND..1
(-2325 -650);
FORCEPROP 3 LASTPIN (-2325 -600) SIG_NAME T1_GND\g
J 0
(-2315 -590);
DISPLAY 0.659574 (-2315 -590);
PAINT MONO (-2315 -590);
DISPLAY INVISIBLE (-2315 -590);
FORCEPROP 1 LAST HDL_POWER T1_GND
J 1
(-2300 -725);
DISPLAY 0.872340 (-2300 -725);
PAINT GREEN (-2300 -725);
FORCEPROP 1 LAST PATH I1
J 0
(-2250 -650);
DISPLAY 0.872340 (-2250 -650);
PAINT AQUA (-2250 -650);
DISPLAY INVISIBLE (-2250 -650);
FORCEPROP 2 LAST CDS_LIB logical_power
J 0
(-2325 -650);
DISPLAY INVISIBLE (-2325 -650);
FORCEADD TP_TDR_4P_FTS..1
R 4
(-575 1025);
FORCEPROP 1 LAST PART_NUMBER TP15
J 0
(-700 1365);
DISPLAY 0.723404 (-700 1365);
PAINT GREEN (-700 1365);
DISPLAY INVISIBLE (-700 1365);
FORCEPROP 2 LAST VALUE TP_TDR_4P_DIP
J 0
(-700 1225);
DISPLAY 1.021277 (-700 1225);
FORCEPROP 2 LAST PACK_TYPE TH
J 0
(-700 1275);
DISPLAY 1.021277 (-700 1275);
FORCEPROP 1 LAST MATERIAL EMPTY
J 0
(-700 1415);
DISPLAY 0.723404 (-700 1415);
PAINT GREEN (-700 1415);
FORCEPROP 1 LAST $LOCATION X42
R 2
J 0
(-450 745);
DISPLAY 0.723404 (-450 745);
PAINT GREEN (-450 745);
FORCEPROP 0 LASTPIN (-300 950) $PN 2
J 0
(-290 960);
DISPLAY 0.680851 (-290 960);
PAINT MONO (-290 960);
FORCEPROP 0 LASTPIN (-300 1100) $PN 3
J 0
(-290 1110);
DISPLAY 0.680851 (-290 1110);
PAINT MONO (-290 1110);
FORCEPROP 0 LASTPIN (-850 950) $PN 1
J 2
(-860 960);
DISPLAY 0.680851 (-860 960);
PAINT MONO (-860 960);
FORCEPROP 0 LASTPIN (-850 1100) $PN 4
J 2
(-860 1110);
DISPLAY 0.680851 (-860 1110);
PAINT MONO (-860 1110);
FORCEPROP 1 LAST NEEDS_NO_SIZE TRUE
R 2
J 0
(-575 1025);
DISPLAY 0.468085 (-575 1025);
PAINT GREEN (-575 1025);
DISPLAY INVISIBLE (-575 1025);
FORCEPROP 1 LAST PATH I10
R 2
J 0
(-675 845);
DISPLAY 0.723404 (-675 845);
PAINT GREEN (-675 845);
DISPLAY INVISIBLE (-675 845);
FORCEPROP 2 LAST CDS_LIB pure_quanta
J 0
(-575 1025);
DISPLAY INVISIBLE (-575 1025);
FORCEPROP 2 LASTPIN (-850 1100) SIG_NAME UN$310$TPTDR4PFTS$I10$S2
J 0
(-840 1110);
DISPLAY 0.659574 (-840 1110);
PAINT MONO (-840 1110);
DISPLAY INVISIBLE (-840 1110);
FORCEPROP 2 LASTPIN (-850 950) SIG_NAME UN$310$TPTDR4PFTS$I10$S1
J 0
(-840 960);
DISPLAY 0.659574 (-840 960);
PAINT MONO (-840 960);
DISPLAY INVISIBLE (-840 960);
FORCEPROP 0 LAST CDS_LOCATION X42
J 0
(-700 1450);
DISPLAY 1.021277 (-700 1450);
DISPLAY INVISIBLE (-700 1450);
FORCEPROP 0 LAST $SEC 1
J 0
(-700 1450);
DISPLAY 0.680851 (-700 1450);
PAINT MONO (-700 1450);
DISPLAY INVISIBLE (-700 1450);
FORCEPROP 0 LAST CDS_SEC 1
J 0
(-700 1450);
DISPLAY 1.021277 (-700 1450);
DISPLAY INVISIBLE (-700 1450);
FORCEADD UNIVERSAL_GND..1
(-175 -650);
FORCEPROP 3 LASTPIN (-175 -600) SIG_NAME T1_GND\g
J 0
(-165 -590);
DISPLAY 0.659574 (-165 -590);
PAINT MONO (-165 -590);
DISPLAY INVISIBLE (-165 -590);
FORCEPROP 1 LAST HDL_POWER T1_GND
J 1
(-150 -725);
DISPLAY 0.872340 (-150 -725);
PAINT GREEN (-150 -725);
FORCEPROP 1 LAST PATH I11
J 0
(-100 -650);
DISPLAY 0.872340 (-100 -650);
PAINT AQUA (-100 -650);
DISPLAY INVISIBLE (-100 -650);
FORCEPROP 2 LAST CDS_LIB logical_power
J 0
(-175 -650);
DISPLAY INVISIBLE (-175 -650);
FORCEADD UNIVERSAL_GND..1
(-175 125);
FORCEPROP 3 LASTPIN (-175 175) SIG_NAME T1_GND\g
J 0
(-165 185);
DISPLAY 0.659574 (-165 185);
PAINT MONO (-165 185);
DISPLAY INVISIBLE (-165 185);
FORCEPROP 1 LAST HDL_POWER T1_GND
J 1
(-150 50);
DISPLAY 0.872340 (-150 50);
PAINT GREEN (-150 50);
FORCEPROP 1 LAST PATH I12
J 0
(-100 125);
DISPLAY 0.872340 (-100 125);
PAINT AQUA (-100 125);
DISPLAY INVISIBLE (-100 125);
FORCEPROP 2 LAST CDS_LIB logical_power
J 0
(-175 125);
DISPLAY INVISIBLE (-175 125);
FORCEADD UNIVERSAL_GND..1
(-175 800);
FORCEPROP 3 LASTPIN (-175 850) SIG_NAME T1_GND\g
J 0
(-165 860);
DISPLAY 0.659574 (-165 860);
PAINT MONO (-165 860);
DISPLAY INVISIBLE (-165 860);
FORCEPROP 1 LAST HDL_POWER T1_GND
J 1
(-150 725);
DISPLAY 0.872340 (-150 725);
PAINT GREEN (-150 725);
FORCEPROP 1 LAST PATH I13
J 0
(-100 800);
DISPLAY 0.872340 (-100 800);
PAINT AQUA (-100 800);
DISPLAY INVISIBLE (-100 800);
FORCEPROP 2 LAST CDS_LIB logical_power
J 0
(-175 800);
DISPLAY INVISIBLE (-175 800);
FORCEADD UNIVERSAL_GND..1
(-175 1575);
FORCEPROP 3 LASTPIN (-175 1625) SIG_NAME T1_GND\g
J 0
(-165 1635);
DISPLAY 0.659574 (-165 1635);
PAINT MONO (-165 1635);
DISPLAY INVISIBLE (-165 1635);
FORCEPROP 1 LAST HDL_POWER T1_GND
J 1
(-150 1500);
DISPLAY 0.872340 (-150 1500);
PAINT GREEN (-150 1500);
FORCEPROP 1 LAST PATH I14
J 0
(-100 1575);
DISPLAY 0.872340 (-100 1575);
PAINT AQUA (-100 1575);
DISPLAY INVISIBLE (-100 1575);
FORCEPROP 2 LAST CDS_LIB logical_power
J 0
(-175 1575);
DISPLAY INVISIBLE (-175 1575);
FORCEADD TP_TDR_4P_FTS..1
R 4
(-575 1800);
FORCEPROP 1 LAST PART_NUMBER TP15
J 0
(-700 2140);
DISPLAY 0.723404 (-700 2140);
PAINT GREEN (-700 2140);
DISPLAY INVISIBLE (-700 2140);
FORCEPROP 1 LAST MATERIAL EMPTY
J 0
(-700 2190);
DISPLAY 0.723404 (-700 2190);
PAINT GREEN (-700 2190);
FORCEPROP 2 LAST PACK_TYPE TH
J 0
(-700 2050);
DISPLAY 1.021277 (-700 2050);
FORCEPROP 2 LAST VALUE TP_TDR_4P_DIP
J 0
(-700 2000);
DISPLAY 1.021277 (-700 2000);
FORCEPROP 1 LAST $LOCATION X41
R 2
J 0
(-450 1520);
DISPLAY 0.723404 (-450 1520);
PAINT GREEN (-450 1520);
FORCEPROP 0 LASTPIN (-300 1725) $PN 2
J 0
(-290 1735);
DISPLAY 0.680851 (-290 1735);
PAINT MONO (-290 1735);
FORCEPROP 0 LASTPIN (-300 1875) $PN 3
J 0
(-290 1885);
DISPLAY 0.680851 (-290 1885);
PAINT MONO (-290 1885);
FORCEPROP 0 LASTPIN (-850 1725) $PN 1
J 2
(-860 1735);
DISPLAY 0.680851 (-860 1735);
PAINT MONO (-860 1735);
FORCEPROP 0 LASTPIN (-850 1875) $PN 4
J 2
(-860 1885);
DISPLAY 0.680851 (-860 1885);
PAINT MONO (-860 1885);
FORCEPROP 1 LAST NEEDS_NO_SIZE TRUE
R 2
J 0
(-575 1800);
DISPLAY 0.468085 (-575 1800);
PAINT GREEN (-575 1800);
DISPLAY INVISIBLE (-575 1800);
FORCEPROP 1 LAST PATH I15
R 2
J 0
(-675 1620);
DISPLAY 0.723404 (-675 1620);
PAINT GREEN (-675 1620);
DISPLAY INVISIBLE (-675 1620);
FORCEPROP 2 LAST CDS_LIB pure_quanta
J 0
(-575 1800);
DISPLAY INVISIBLE (-575 1800);
FORCEPROP 2 LASTPIN (-850 1875) SIG_NAME UN$310$TPTDR4PFTS$I15$S2
J 0
(-840 1885);
DISPLAY 0.659574 (-840 1885);
PAINT MONO (-840 1885);
DISPLAY INVISIBLE (-840 1885);
FORCEPROP 2 LASTPIN (-850 1725) SIG_NAME UN$310$TPTDR4PFTS$I15$S1
J 0
(-840 1735);
DISPLAY 0.659574 (-840 1735);
PAINT MONO (-840 1735);
DISPLAY INVISIBLE (-840 1735);
FORCEPROP 0 LAST CDS_LOCATION X41
J 0
(-700 2225);
DISPLAY 1.021277 (-700 2225);
DISPLAY INVISIBLE (-700 2225);
FORCEPROP 0 LAST $SEC 1
J 0
(-700 2225);
DISPLAY 0.680851 (-700 2225);
PAINT MONO (-700 2225);
DISPLAY INVISIBLE (-700 2225);
FORCEPROP 0 LAST CDS_SEC 1
J 0
(-700 2225);
DISPLAY 1.021277 (-700 2225);
DISPLAY INVISIBLE (-700 2225);
FORCEADD TP_TDR_4P_FTS..1
(-1900 1800);
FORCEPROP 1 LAST PART_NUMBER TP15
J 0
(-2025 2035);
DISPLAY 0.723404 (-2025 2035);
PAINT GREEN (-2025 2035);
DISPLAY INVISIBLE (-2025 2035);
FORCEPROP 1 LAST MATERIAL EMPTY
J 0
(-2025 1985);
DISPLAY 0.723404 (-2025 1985);
PAINT GREEN (-2025 1985);
FORCEPROP 2 LAST PACK_TYPE TH
J 0
(-2025 2125);
DISPLAY 1.021277 (-2025 2125);
FORCEPROP 2 LAST VALUE TP_TDR_4P_DIP
J 0
(-2025 2175);
DISPLAY 1.021277 (-2025 2175);
FORCEPROP 1 LAST $LOCATION X35
J 0
(-2025 2080);
DISPLAY 0.723404 (-2025 2080);
PAINT GREEN (-2025 2080);
FORCEPROP 0 LASTPIN (-2175 1875) $PN 2
J 2
(-2185 1885);
DISPLAY 0.680851 (-2185 1885);
PAINT MONO (-2185 1885);
FORCEPROP 0 LASTPIN (-2175 1725) $PN 3
J 2
(-2185 1735);
DISPLAY 0.680851 (-2185 1735);
PAINT MONO (-2185 1735);
FORCEPROP 0 LASTPIN (-1625 1875) $PN 1
J 0
(-1615 1885);
DISPLAY 0.680851 (-1615 1885);
PAINT MONO (-1615 1885);
FORCEPROP 0 LASTPIN (-1625 1725) $PN 4
J 0
(-1615 1735);
DISPLAY 0.680851 (-1615 1735);
PAINT MONO (-1615 1735);
FORCEPROP 1 LAST NEEDS_NO_SIZE TRUE
J 0
(-1900 1800);
DISPLAY 0.468085 (-1900 1800);
PAINT GREEN (-1900 1800);
DISPLAY INVISIBLE (-1900 1800);
FORCEPROP 1 LAST PATH I16
J 0
(-1800 1980);
DISPLAY 0.723404 (-1800 1980);
PAINT GREEN (-1800 1980);
DISPLAY INVISIBLE (-1800 1980);
FORCEPROP 2 LAST CDS_LIB pure_quanta
J 0
(-1900 1800);
DISPLAY INVISIBLE (-1900 1800);
FORCEPROP 0 LAST CDS_LOCATION X35
J 0
(-2025 2225);
DISPLAY 1.021277 (-2025 2225);
DISPLAY INVISIBLE (-2025 2225);
FORCEPROP 0 LAST $SEC 1
J 0
(-2025 2225);
DISPLAY 0.680851 (-2025 2225);
PAINT MONO (-2025 2225);
DISPLAY INVISIBLE (-2025 2225);
FORCEPROP 0 LAST CDS_SEC 1
J 0
(-2025 2225);
DISPLAY 1.021277 (-2025 2225);
DISPLAY INVISIBLE (-2025 2225);
FORCEADD UNIVERSAL_GND..1
(-2325 2350);
FORCEPROP 3 LASTPIN (-2325 2400) SIG_NAME T1_GND\g
J 0
(-2315 2410);
DISPLAY 0.659574 (-2315 2410);
PAINT MONO (-2315 2410);
DISPLAY INVISIBLE (-2315 2410);
FORCEPROP 1 LAST HDL_POWER T1_GND
J 1
(-2300 2275);
DISPLAY 0.872340 (-2300 2275);
PAINT GREEN (-2300 2275);
FORCEPROP 1 LAST PATH I17
J 0
(-2250 2350);
DISPLAY 0.872340 (-2250 2350);
PAINT AQUA (-2250 2350);
DISPLAY INVISIBLE (-2250 2350);
FORCEPROP 2 LAST CDS_LIB logical_power
J 0
(-2325 2350);
DISPLAY INVISIBLE (-2325 2350);
FORCEADD UNIVERSAL_GND..1
(-2325 3125);
FORCEPROP 3 LASTPIN (-2325 3175) SIG_NAME T1_GND\g
J 0
(-2315 3185);
DISPLAY 0.659574 (-2315 3185);
PAINT MONO (-2315 3185);
DISPLAY INVISIBLE (-2315 3185);
FORCEPROP 1 LAST HDL_POWER T1_GND
J 1
(-2300 3050);
DISPLAY 0.872340 (-2300 3050);
PAINT GREEN (-2300 3050);
FORCEPROP 1 LAST PATH I18
J 0
(-2250 3125);
DISPLAY 0.872340 (-2250 3125);
PAINT AQUA (-2250 3125);
DISPLAY INVISIBLE (-2250 3125);
FORCEPROP 2 LAST CDS_LIB logical_power
J 0
(-2325 3125);
DISPLAY INVISIBLE (-2325 3125);
FORCEADD TP_TDR_4P_FTS..1
(-1900 2575);
FORCEPROP 1 LAST PART_NUMBER TP15
J 0
(-2025 2810);
DISPLAY 0.723404 (-2025 2810);
PAINT GREEN (-2025 2810);
DISPLAY INVISIBLE (-2025 2810);
FORCEPROP 1 LAST MATERIAL EMPTY
J 0
(-2025 2760);
DISPLAY 0.723404 (-2025 2760);
PAINT GREEN (-2025 2760);
FORCEPROP 2 LAST PACK_TYPE TH
J 0
(-2025 2900);
DISPLAY 1.021277 (-2025 2900);
FORCEPROP 2 LAST VALUE TP_TDR_4P_DIP
J 0
(-2025 2950);
DISPLAY 1.021277 (-2025 2950);
FORCEPROP 1 LAST $LOCATION X34
J 0
(-2025 2855);
DISPLAY 0.723404 (-2025 2855);
PAINT GREEN (-2025 2855);
FORCEPROP 0 LASTPIN (-2175 2650) $PN 2
J 2
(-2185 2660);
DISPLAY 0.680851 (-2185 2660);
PAINT MONO (-2185 2660);
FORCEPROP 0 LASTPIN (-2175 2500) $PN 3
J 2
(-2185 2510);
DISPLAY 0.680851 (-2185 2510);
PAINT MONO (-2185 2510);
FORCEPROP 0 LASTPIN (-1625 2650) $PN 1
J 0
(-1615 2660);
DISPLAY 0.680851 (-1615 2660);
PAINT MONO (-1615 2660);
FORCEPROP 0 LASTPIN (-1625 2500) $PN 4
J 0
(-1615 2510);
DISPLAY 0.680851 (-1615 2510);
PAINT MONO (-1615 2510);
FORCEPROP 1 LAST NEEDS_NO_SIZE TRUE
J 0
(-1900 2575);
DISPLAY 0.468085 (-1900 2575);
PAINT GREEN (-1900 2575);
DISPLAY INVISIBLE (-1900 2575);
FORCEPROP 1 LAST PATH I19
J 0
(-1800 2755);
DISPLAY 0.723404 (-1800 2755);
PAINT GREEN (-1800 2755);
DISPLAY INVISIBLE (-1800 2755);
FORCEPROP 2 LAST CDS_LIB pure_quanta
J 0
(-1900 2575);
DISPLAY INVISIBLE (-1900 2575);
FORCEPROP 2 LASTPIN (-1625 2500) SIG_NAME UN$310$TPTDR4PFTS$I19$S2
J 0
(-1615 2510);
DISPLAY 0.659574 (-1615 2510);
PAINT MONO (-1615 2510);
DISPLAY INVISIBLE (-1615 2510);
FORCEPROP 2 LASTPIN (-1625 2650) SIG_NAME UN$310$TPTDR4PFTS$I19$S1
J 0
(-1615 2660);
DISPLAY 0.659574 (-1615 2660);
PAINT MONO (-1615 2660);
DISPLAY INVISIBLE (-1615 2660);
FORCEPROP 0 LAST CDS_LOCATION X34
J 0
(-2025 3000);
DISPLAY 1.021277 (-2025 3000);
DISPLAY INVISIBLE (-2025 3000);
FORCEPROP 0 LAST $SEC 1
J 0
(-2025 3000);
DISPLAY 0.680851 (-2025 3000);
PAINT MONO (-2025 3000);
DISPLAY INVISIBLE (-2025 3000);
FORCEPROP 0 LAST CDS_SEC 1
J 0
(-2025 3000);
DISPLAY 1.021277 (-2025 3000);
DISPLAY INVISIBLE (-2025 3000);
FORCEADD UNIVERSAL_GND..1
(-2325 125);
FORCEPROP 3 LASTPIN (-2325 175) SIG_NAME T1_GND\g
J 0
(-2315 185);
DISPLAY 0.659574 (-2315 185);
PAINT MONO (-2315 185);
DISPLAY INVISIBLE (-2315 185);
FORCEPROP 1 LAST HDL_POWER T1_GND
J 1
(-2300 50);
DISPLAY 0.872340 (-2300 50);
PAINT GREEN (-2300 50);
FORCEPROP 1 LAST PATH I2
J 0
(-2250 125);
DISPLAY 0.872340 (-2250 125);
PAINT AQUA (-2250 125);
DISPLAY INVISIBLE (-2250 125);
FORCEPROP 2 LAST CDS_LIB logical_power
J 0
(-2325 125);
DISPLAY INVISIBLE (-2325 125);
FORCEADD TP_TDR_4P_FTS..1
(-1900 3350);
FORCEPROP 1 LAST PART_NUMBER TP15
J 0
(-2025 3585);
DISPLAY 0.723404 (-2025 3585);
PAINT GREEN (-2025 3585);
DISPLAY INVISIBLE (-2025 3585);
FORCEPROP 1 LAST MATERIAL EMPTY
J 0
(-2025 3535);
DISPLAY 0.723404 (-2025 3535);
PAINT GREEN (-2025 3535);
FORCEPROP 2 LAST PACK_TYPE TH
J 0
(-2025 3675);
DISPLAY 1.021277 (-2025 3675);
FORCEPROP 2 LAST VALUE TP_TDR_4P_DIP
J 0
(-2025 3725);
DISPLAY 1.021277 (-2025 3725);
FORCEPROP 1 LAST $LOCATION X33
J 0
(-2025 3630);
DISPLAY 0.723404 (-2025 3630);
PAINT GREEN (-2025 3630);
FORCEPROP 0 LASTPIN (-2175 3425) $PN 2
J 2
(-2185 3435);
DISPLAY 0.680851 (-2185 3435);
PAINT MONO (-2185 3435);
FORCEPROP 0 LASTPIN (-2175 3275) $PN 3
J 2
(-2185 3285);
DISPLAY 0.680851 (-2185 3285);
PAINT MONO (-2185 3285);
FORCEPROP 0 LASTPIN (-1625 3425) $PN 1
J 0
(-1615 3435);
DISPLAY 0.680851 (-1615 3435);
PAINT MONO (-1615 3435);
FORCEPROP 0 LASTPIN (-1625 3275) $PN 4
J 0
(-1615 3285);
DISPLAY 0.680851 (-1615 3285);
PAINT MONO (-1615 3285);
FORCEPROP 1 LAST NEEDS_NO_SIZE TRUE
J 0
(-1900 3350);
DISPLAY 0.468085 (-1900 3350);
PAINT GREEN (-1900 3350);
DISPLAY INVISIBLE (-1900 3350);
FORCEPROP 1 LAST PATH I20
J 0
(-1800 3530);
DISPLAY 0.723404 (-1800 3530);
PAINT GREEN (-1800 3530);
DISPLAY INVISIBLE (-1800 3530);
FORCEPROP 2 LAST CDS_LIB pure_quanta
J 0
(-1900 3350);
DISPLAY INVISIBLE (-1900 3350);
FORCEPROP 2 LASTPIN (-1625 3275) SIG_NAME UN$310$TPTDR4PFTS$I20$S2
J 0
(-1615 3285);
DISPLAY 0.659574 (-1615 3285);
PAINT MONO (-1615 3285);
DISPLAY INVISIBLE (-1615 3285);
FORCEPROP 2 LASTPIN (-1625 3425) SIG_NAME UN$310$TPTDR4PFTS$I20$S1
J 0
(-1615 3435);
DISPLAY 0.659574 (-1615 3435);
PAINT MONO (-1615 3435);
DISPLAY INVISIBLE (-1615 3435);
FORCEPROP 0 LAST CDS_LOCATION X33
J 0
(-2025 3775);
DISPLAY 1.021277 (-2025 3775);
DISPLAY INVISIBLE (-2025 3775);
FORCEPROP 0 LAST $SEC 1
J 0
(-2025 3775);
DISPLAY 0.680851 (-2025 3775);
PAINT MONO (-2025 3775);
DISPLAY INVISIBLE (-2025 3775);
FORCEPROP 0 LAST CDS_SEC 1
J 0
(-2025 3775);
DISPLAY 1.021277 (-2025 3775);
DISPLAY INVISIBLE (-2025 3775);
FORCEADD TP_TDR_4P_FTS..1
R 4
(-575 2575);
FORCEPROP 1 LAST PART_NUMBER TP15
J 0
(-700 2915);
DISPLAY 0.723404 (-700 2915);
PAINT GREEN (-700 2915);
DISPLAY INVISIBLE (-700 2915);
FORCEPROP 2 LAST VALUE TP_TDR_4P_DIP
J 0
(-700 2775);
DISPLAY 1.021277 (-700 2775);
FORCEPROP 1 LAST MATERIAL EMPTY
J 0
(-700 2965);
DISPLAY 0.723404 (-700 2965);
PAINT GREEN (-700 2965);
FORCEPROP 2 LAST PACK_TYPE TH
J 0
(-700 2825);
DISPLAY 1.021277 (-700 2825);
FORCEPROP 1 LAST $LOCATION X40
R 2
J 0
(-450 2295);
DISPLAY 0.723404 (-450 2295);
PAINT GREEN (-450 2295);
FORCEPROP 0 LASTPIN (-300 2500) $PN 2
J 0
(-290 2510);
DISPLAY 0.680851 (-290 2510);
PAINT MONO (-290 2510);
FORCEPROP 0 LASTPIN (-300 2650) $PN 3
J 0
(-290 2660);
DISPLAY 0.680851 (-290 2660);
PAINT MONO (-290 2660);
FORCEPROP 0 LASTPIN (-850 2500) $PN 1
J 2
(-860 2510);
DISPLAY 0.680851 (-860 2510);
PAINT MONO (-860 2510);
FORCEPROP 0 LASTPIN (-850 2650) $PN 4
J 2
(-860 2660);
DISPLAY 0.680851 (-860 2660);
PAINT MONO (-860 2660);
FORCEPROP 1 LAST NEEDS_NO_SIZE TRUE
R 2
J 0
(-575 2575);
DISPLAY 0.468085 (-575 2575);
PAINT GREEN (-575 2575);
DISPLAY INVISIBLE (-575 2575);
FORCEPROP 1 LAST PATH I21
R 2
J 0
(-675 2395);
DISPLAY 0.723404 (-675 2395);
PAINT GREEN (-675 2395);
DISPLAY INVISIBLE (-675 2395);
FORCEPROP 2 LAST CDS_LIB pure_quanta
J 0
(-575 2575);
DISPLAY INVISIBLE (-575 2575);
FORCEPROP 0 LAST CDS_LOCATION X40
J 0
(-700 3000);
DISPLAY 1.021277 (-700 3000);
DISPLAY INVISIBLE (-700 3000);
FORCEPROP 0 LAST $SEC 1
J 0
(-700 3000);
DISPLAY 0.680851 (-700 3000);
PAINT MONO (-700 3000);
DISPLAY INVISIBLE (-700 3000);
FORCEPROP 0 LAST CDS_SEC 1
J 0
(-700 3000);
DISPLAY 1.021277 (-700 3000);
DISPLAY INVISIBLE (-700 3000);
FORCEADD TP_TDR_4P_FTS..1
R 4
(-575 3350);
FORCEPROP 1 LAST PART_NUMBER TP15
J 0
(-700 3690);
DISPLAY 0.723404 (-700 3690);
PAINT GREEN (-700 3690);
DISPLAY INVISIBLE (-700 3690);
FORCEPROP 2 LAST VALUE TP_TDR_4P_DIP
J 0
(-700 3550);
DISPLAY 1.021277 (-700 3550);
FORCEPROP 2 LAST PACK_TYPE TH
J 0
(-700 3600);
DISPLAY 1.021277 (-700 3600);
FORCEPROP 1 LAST MATERIAL EMPTY
J 0
(-700 3740);
DISPLAY 0.723404 (-700 3740);
PAINT GREEN (-700 3740);
FORCEPROP 1 LAST $LOCATION X39
R 2
J 0
(-450 3070);
DISPLAY 0.723404 (-450 3070);
PAINT GREEN (-450 3070);
FORCEPROP 0 LASTPIN (-300 3275) $PN 2
J 0
(-290 3285);
DISPLAY 0.680851 (-290 3285);
PAINT MONO (-290 3285);
FORCEPROP 0 LASTPIN (-300 3425) $PN 3
J 0
(-290 3435);
DISPLAY 0.680851 (-290 3435);
PAINT MONO (-290 3435);
FORCEPROP 0 LASTPIN (-850 3275) $PN 1
J 2
(-860 3285);
DISPLAY 0.680851 (-860 3285);
PAINT MONO (-860 3285);
FORCEPROP 0 LASTPIN (-850 3425) $PN 4
J 2
(-860 3435);
DISPLAY 0.680851 (-860 3435);
PAINT MONO (-860 3435);
FORCEPROP 1 LAST NEEDS_NO_SIZE TRUE
R 2
J 0
(-575 3350);
DISPLAY 0.468085 (-575 3350);
PAINT GREEN (-575 3350);
DISPLAY INVISIBLE (-575 3350);
FORCEPROP 1 LAST PATH I22
R 2
J 0
(-675 3170);
DISPLAY 0.723404 (-675 3170);
PAINT GREEN (-675 3170);
DISPLAY INVISIBLE (-675 3170);
FORCEPROP 2 LAST CDS_LIB pure_quanta
J 0
(-575 3350);
DISPLAY INVISIBLE (-575 3350);
FORCEPROP 0 LAST CDS_LOCATION X39
J 0
(-700 3775);
DISPLAY 1.021277 (-700 3775);
DISPLAY INVISIBLE (-700 3775);
FORCEPROP 0 LAST $SEC 1
J 0
(-700 3775);
DISPLAY 0.680851 (-700 3775);
PAINT MONO (-700 3775);
DISPLAY INVISIBLE (-700 3775);
FORCEPROP 0 LAST CDS_SEC 1
J 0
(-700 3775);
DISPLAY 1.021277 (-700 3775);
DISPLAY INVISIBLE (-700 3775);
FORCEADD UNIVERSAL_GND..1
(-175 2350);
FORCEPROP 3 LASTPIN (-175 2400) SIG_NAME T1_GND\g
J 0
(-165 2410);
DISPLAY 0.659574 (-165 2410);
PAINT MONO (-165 2410);
DISPLAY INVISIBLE (-165 2410);
FORCEPROP 1 LAST HDL_POWER T1_GND
J 1
(-150 2275);
DISPLAY 0.872340 (-150 2275);
PAINT GREEN (-150 2275);
FORCEPROP 1 LAST PATH I23
J 0
(-100 2350);
DISPLAY 0.872340 (-100 2350);
PAINT AQUA (-100 2350);
DISPLAY INVISIBLE (-100 2350);
FORCEPROP 2 LAST CDS_LIB logical_power
J 0
(-175 2350);
DISPLAY INVISIBLE (-175 2350);
FORCEADD UNIVERSAL_GND..1
(-175 3125);
FORCEPROP 3 LASTPIN (-175 3175) SIG_NAME T1_GND\g
J 0
(-165 3185);
DISPLAY 0.659574 (-165 3185);
PAINT MONO (-165 3185);
DISPLAY INVISIBLE (-165 3185);
FORCEPROP 1 LAST HDL_POWER T1_GND
J 1
(-150 3050);
DISPLAY 0.872340 (-150 3050);
PAINT GREEN (-150 3050);
FORCEPROP 1 LAST PATH I24
J 0
(-100 3125);
DISPLAY 0.872340 (-100 3125);
PAINT AQUA (-100 3125);
DISPLAY INVISIBLE (-100 3125);
FORCEPROP 2 LAST CDS_LIB logical_power
J 0
(-175 3125);
DISPLAY INVISIBLE (-175 3125);
FORCEADD UNIVERSAL_GND..1
(-2325 800);
FORCEPROP 3 LASTPIN (-2325 850) SIG_NAME T1_GND\g
J 0
(-2315 860);
DISPLAY 0.659574 (-2315 860);
PAINT MONO (-2315 860);
DISPLAY INVISIBLE (-2315 860);
FORCEPROP 1 LAST HDL_POWER T1_GND
J 1
(-2300 725);
DISPLAY 0.872340 (-2300 725);
PAINT GREEN (-2300 725);
FORCEPROP 1 LAST PATH I3
J 0
(-2250 800);
DISPLAY 0.872340 (-2250 800);
PAINT AQUA (-2250 800);
DISPLAY INVISIBLE (-2250 800);
FORCEPROP 2 LAST CDS_LIB logical_power
J 0
(-2325 800);
DISPLAY INVISIBLE (-2325 800);
FORCEADD UNIVERSAL_GND..1
(-2325 1575);
FORCEPROP 3 LASTPIN (-2325 1625) SIG_NAME T1_GND\g
J 0
(-2315 1635);
DISPLAY 0.659574 (-2315 1635);
PAINT MONO (-2315 1635);
DISPLAY INVISIBLE (-2315 1635);
FORCEPROP 1 LAST HDL_POWER T1_GND
J 1
(-2300 1500);
DISPLAY 0.872340 (-2300 1500);
PAINT GREEN (-2300 1500);
FORCEPROP 1 LAST PATH I4
J 0
(-2250 1575);
DISPLAY 0.872340 (-2250 1575);
PAINT AQUA (-2250 1575);
DISPLAY INVISIBLE (-2250 1575);
FORCEPROP 2 LAST CDS_LIB logical_power
J 0
(-2325 1575);
DISPLAY INVISIBLE (-2325 1575);
FORCEADD TP_TDR_4P_FTS..1
(-1900 -425);
FORCEPROP 1 LAST PART_NUMBER TP15
J 0
(-2025 -190);
DISPLAY 0.723404 (-2025 -190);
PAINT GREEN (-2025 -190);
DISPLAY INVISIBLE (-2025 -190);
FORCEPROP 2 LAST VALUE TP_TDR_4P_DIP
J 0
(-2025 -50);
DISPLAY 1.021277 (-2025 -50);
FORCEPROP 2 LAST PACK_TYPE TH
J 0
(-2025 -100);
DISPLAY 1.021277 (-2025 -100);
FORCEPROP 1 LAST MATERIAL EMPTY
J 0
(-2025 -240);
DISPLAY 0.723404 (-2025 -240);
PAINT GREEN (-2025 -240);
FORCEPROP 1 LAST $LOCATION X38
J 0
(-2025 -145);
DISPLAY 0.723404 (-2025 -145);
PAINT GREEN (-2025 -145);
FORCEPROP 0 LASTPIN (-2175 -350) $PN 2
J 2
(-2185 -340);
DISPLAY 0.680851 (-2185 -340);
PAINT MONO (-2185 -340);
FORCEPROP 0 LASTPIN (-2175 -500) $PN 3
J 2
(-2185 -490);
DISPLAY 0.680851 (-2185 -490);
PAINT MONO (-2185 -490);
FORCEPROP 0 LASTPIN (-1625 -350) $PN 1
J 0
(-1615 -340);
DISPLAY 0.680851 (-1615 -340);
PAINT MONO (-1615 -340);
FORCEPROP 0 LASTPIN (-1625 -500) $PN 4
J 0
(-1615 -490);
DISPLAY 0.680851 (-1615 -490);
PAINT MONO (-1615 -490);
FORCEPROP 1 LAST NEEDS_NO_SIZE TRUE
J 0
(-1900 -425);
DISPLAY 0.468085 (-1900 -425);
PAINT GREEN (-1900 -425);
DISPLAY INVISIBLE (-1900 -425);
FORCEPROP 1 LAST PATH I5
J 0
(-1800 -245);
DISPLAY 0.723404 (-1800 -245);
PAINT GREEN (-1800 -245);
DISPLAY INVISIBLE (-1800 -245);
FORCEPROP 2 LAST CDS_LIB pure_quanta
J 0
(-1900 -425);
DISPLAY INVISIBLE (-1900 -425);
FORCEPROP 2 LASTPIN (-1625 -350) SIG_NAME UN$310$TPTDR4PFTS$I5$S1
J 0
(-1615 -340);
DISPLAY 0.659574 (-1615 -340);
PAINT MONO (-1615 -340);
DISPLAY INVISIBLE (-1615 -340);
FORCEPROP 2 LASTPIN (-1625 -500) SIG_NAME UN$310$TPTDR4PFTS$I5$S2
J 0
(-1615 -490);
DISPLAY 0.659574 (-1615 -490);
PAINT MONO (-1615 -490);
DISPLAY INVISIBLE (-1615 -490);
FORCEPROP 0 LAST CDS_LOCATION X38
J 0
(-2025 0);
DISPLAY 1.021277 (-2025 0);
DISPLAY INVISIBLE (-2025 0);
FORCEPROP 0 LAST $SEC 1
J 0
(-2025 0);
DISPLAY 0.680851 (-2025 0);
PAINT MONO (-2025 0);
DISPLAY INVISIBLE (-2025 0);
FORCEPROP 0 LAST CDS_SEC 1
J 0
(-2025 0);
DISPLAY 1.021277 (-2025 0);
DISPLAY INVISIBLE (-2025 0);
FORCEADD TP_TDR_4P_FTS..1
R 4
(-575 -425);
FORCEPROP 1 LAST PART_NUMBER TP15
J 0
(-700 -85);
DISPLAY 0.723404 (-700 -85);
PAINT GREEN (-700 -85);
DISPLAY INVISIBLE (-700 -85);
FORCEPROP 2 LAST PACK_TYPE TH
J 0
(-700 -175);
DISPLAY 1.021277 (-700 -175);
FORCEPROP 1 LAST MATERIAL EMPTY
J 0
(-700 -35);
DISPLAY 0.723404 (-700 -35);
PAINT GREEN (-700 -35);
FORCEPROP 2 LAST VALUE TP_TDR_4P_DIP
J 0
(-700 -225);
DISPLAY 1.021277 (-700 -225);
FORCEPROP 1 LAST $LOCATION X44
R 2
J 0
(-450 -705);
DISPLAY 0.723404 (-450 -705);
PAINT GREEN (-450 -705);
FORCEPROP 0 LASTPIN (-300 -500) $PN 2
J 0
(-290 -490);
DISPLAY 0.680851 (-290 -490);
PAINT MONO (-290 -490);
FORCEPROP 0 LASTPIN (-300 -350) $PN 3
J 0
(-290 -340);
DISPLAY 0.680851 (-290 -340);
PAINT MONO (-290 -340);
FORCEPROP 0 LASTPIN (-850 -500) $PN 1
J 2
(-860 -490);
DISPLAY 0.680851 (-860 -490);
PAINT MONO (-860 -490);
FORCEPROP 0 LASTPIN (-850 -350) $PN 4
J 2
(-860 -340);
DISPLAY 0.680851 (-860 -340);
PAINT MONO (-860 -340);
FORCEPROP 1 LAST NEEDS_NO_SIZE TRUE
R 2
J 0
(-575 -425);
DISPLAY 0.468085 (-575 -425);
PAINT GREEN (-575 -425);
DISPLAY INVISIBLE (-575 -425);
FORCEPROP 1 LAST PATH I6
R 2
J 0
(-675 -605);
DISPLAY 0.723404 (-675 -605);
PAINT GREEN (-675 -605);
DISPLAY INVISIBLE (-675 -605);
FORCEPROP 2 LAST CDS_LIB pure_quanta
J 0
(-575 -425);
DISPLAY INVISIBLE (-575 -425);
FORCEPROP 0 LAST CDS_LOCATION X44
J 0
(-700 0);
DISPLAY 1.021277 (-700 0);
DISPLAY INVISIBLE (-700 0);
FORCEPROP 0 LAST $SEC 1
J 0
(-700 0);
DISPLAY 0.680851 (-700 0);
PAINT MONO (-700 0);
DISPLAY INVISIBLE (-700 0);
FORCEPROP 0 LAST CDS_SEC 1
J 0
(-700 0);
DISPLAY 1.021277 (-700 0);
DISPLAY INVISIBLE (-700 0);
FORCEADD TP_TDR_4P_FTS..1
(-1900 350);
FORCEPROP 1 LAST PART_NUMBER TP15
J 0
(-2025 585);
DISPLAY 0.723404 (-2025 585);
PAINT GREEN (-2025 585);
DISPLAY INVISIBLE (-2025 585);
FORCEPROP 1 LAST MATERIAL EMPTY
J 0
(-2025 535);
DISPLAY 0.723404 (-2025 535);
PAINT GREEN (-2025 535);
FORCEPROP 2 LAST PACK_TYPE TH
J 0
(-2025 675);
DISPLAY 1.021277 (-2025 675);
FORCEPROP 2 LAST VALUE TP_TDR_4P_DIP
J 0
(-2025 725);
DISPLAY 1.021277 (-2025 725);
FORCEPROP 1 LAST $LOCATION X37
J 0
(-2025 630);
DISPLAY 0.723404 (-2025 630);
PAINT GREEN (-2025 630);
FORCEPROP 0 LASTPIN (-2175 425) $PN 2
J 2
(-2185 435);
DISPLAY 0.680851 (-2185 435);
PAINT MONO (-2185 435);
FORCEPROP 0 LASTPIN (-2175 275) $PN 3
J 2
(-2185 285);
DISPLAY 0.680851 (-2185 285);
PAINT MONO (-2185 285);
FORCEPROP 0 LASTPIN (-1625 425) $PN 1
J 0
(-1615 435);
DISPLAY 0.680851 (-1615 435);
PAINT MONO (-1615 435);
FORCEPROP 0 LASTPIN (-1625 275) $PN 4
J 0
(-1615 285);
DISPLAY 0.680851 (-1615 285);
PAINT MONO (-1615 285);
FORCEPROP 1 LAST NEEDS_NO_SIZE TRUE
J 0
(-1900 350);
DISPLAY 0.468085 (-1900 350);
PAINT GREEN (-1900 350);
DISPLAY INVISIBLE (-1900 350);
FORCEPROP 1 LAST PATH I7
J 0
(-1800 530);
DISPLAY 0.723404 (-1800 530);
PAINT GREEN (-1800 530);
DISPLAY INVISIBLE (-1800 530);
FORCEPROP 2 LAST CDS_LIB pure_quanta
J 0
(-1900 350);
DISPLAY INVISIBLE (-1900 350);
FORCEPROP 2 LASTPIN (-1625 275) SIG_NAME UN$310$TPTDR4PFTS$I7$S2
J 0
(-1615 285);
DISPLAY 0.659574 (-1615 285);
PAINT MONO (-1615 285);
DISPLAY INVISIBLE (-1615 285);
FORCEPROP 2 LASTPIN (-1625 425) SIG_NAME UN$310$TPTDR4PFTS$I7$S1
J 0
(-1615 435);
DISPLAY 0.659574 (-1615 435);
PAINT MONO (-1615 435);
DISPLAY INVISIBLE (-1615 435);
FORCEPROP 0 LAST CDS_LOCATION X37
J 0
(-2025 775);
DISPLAY 1.021277 (-2025 775);
DISPLAY INVISIBLE (-2025 775);
FORCEPROP 0 LAST $SEC 1
J 0
(-2025 775);
DISPLAY 0.680851 (-2025 775);
PAINT MONO (-2025 775);
DISPLAY INVISIBLE (-2025 775);
FORCEPROP 0 LAST CDS_SEC 1
J 0
(-2025 775);
DISPLAY 1.021277 (-2025 775);
DISPLAY INVISIBLE (-2025 775);
FORCEADD TP_TDR_4P_FTS..1
(-1900 1025);
FORCEPROP 1 LAST PART_NUMBER TP15
J 0
(-2025 1260);
DISPLAY 0.723404 (-2025 1260);
PAINT GREEN (-2025 1260);
DISPLAY INVISIBLE (-2025 1260);
FORCEPROP 2 LAST VALUE TP_TDR_4P_DIP
J 0
(-2025 1400);
DISPLAY 1.021277 (-2025 1400);
FORCEPROP 2 LAST PACK_TYPE TH
J 0
(-2025 1350);
DISPLAY 1.021277 (-2025 1350);
FORCEPROP 1 LAST MATERIAL EMPTY
J 0
(-2025 1210);
DISPLAY 0.723404 (-2025 1210);
PAINT GREEN (-2025 1210);
FORCEPROP 1 LAST $LOCATION X36
J 0
(-2025 1305);
DISPLAY 0.723404 (-2025 1305);
PAINT GREEN (-2025 1305);
FORCEPROP 0 LASTPIN (-2175 1100) $PN 2
J 2
(-2185 1110);
DISPLAY 0.680851 (-2185 1110);
PAINT MONO (-2185 1110);
FORCEPROP 0 LASTPIN (-2175 950) $PN 3
J 2
(-2185 960);
DISPLAY 0.680851 (-2185 960);
PAINT MONO (-2185 960);
FORCEPROP 0 LASTPIN (-1625 1100) $PN 1
J 0
(-1615 1110);
DISPLAY 0.680851 (-1615 1110);
PAINT MONO (-1615 1110);
FORCEPROP 0 LASTPIN (-1625 950) $PN 4
J 0
(-1615 960);
DISPLAY 0.680851 (-1615 960);
PAINT MONO (-1615 960);
FORCEPROP 1 LAST NEEDS_NO_SIZE TRUE
J 0
(-1900 1025);
DISPLAY 0.468085 (-1900 1025);
PAINT GREEN (-1900 1025);
DISPLAY INVISIBLE (-1900 1025);
FORCEPROP 1 LAST PATH I8
J 0
(-1800 1205);
DISPLAY 0.723404 (-1800 1205);
PAINT GREEN (-1800 1205);
DISPLAY INVISIBLE (-1800 1205);
FORCEPROP 2 LAST CDS_LIB pure_quanta
J 0
(-1900 1025);
DISPLAY INVISIBLE (-1900 1025);
FORCEPROP 0 LAST CDS_LOCATION X36
J 0
(-2025 1450);
DISPLAY 1.021277 (-2025 1450);
DISPLAY INVISIBLE (-2025 1450);
FORCEPROP 0 LAST $SEC 1
J 0
(-2025 1450);
DISPLAY 0.680851 (-2025 1450);
PAINT MONO (-2025 1450);
DISPLAY INVISIBLE (-2025 1450);
FORCEPROP 0 LAST CDS_SEC 1
J 0
(-2025 1450);
DISPLAY 1.021277 (-2025 1450);
DISPLAY INVISIBLE (-2025 1450);
FORCEADD TP_TDR_4P_FTS..1
R 4
(-575 350);
FORCEPROP 1 LAST PART_NUMBER TP15
J 0
(-700 690);
DISPLAY 0.723404 (-700 690);
PAINT GREEN (-700 690);
DISPLAY INVISIBLE (-700 690);
FORCEPROP 2 LAST VALUE TP_TDR_4P_DIP
J 0
(-700 550);
DISPLAY 1.021277 (-700 550);
FORCEPROP 1 LAST MATERIAL EMPTY
J 0
(-700 740);
DISPLAY 0.723404 (-700 740);
PAINT GREEN (-700 740);
FORCEPROP 2 LAST PACK_TYPE TH
J 0
(-700 600);
DISPLAY 1.021277 (-700 600);
FORCEPROP 1 LAST $LOCATION X43
R 2
J 0
(-450 70);
DISPLAY 0.723404 (-450 70);
PAINT GREEN (-450 70);
FORCEPROP 0 LASTPIN (-300 275) $PN 2
J 0
(-290 285);
DISPLAY 0.680851 (-290 285);
PAINT MONO (-290 285);
FORCEPROP 0 LASTPIN (-300 425) $PN 3
J 0
(-290 435);
DISPLAY 0.680851 (-290 435);
PAINT MONO (-290 435);
FORCEPROP 0 LASTPIN (-850 275) $PN 1
J 2
(-860 285);
DISPLAY 0.680851 (-860 285);
PAINT MONO (-860 285);
FORCEPROP 0 LASTPIN (-850 425) $PN 4
J 2
(-860 435);
DISPLAY 0.680851 (-860 435);
PAINT MONO (-860 435);
FORCEPROP 1 LAST NEEDS_NO_SIZE TRUE
R 2
J 0
(-575 350);
DISPLAY 0.468085 (-575 350);
PAINT GREEN (-575 350);
DISPLAY INVISIBLE (-575 350);
FORCEPROP 1 LAST PATH I9
R 2
J 0
(-675 170);
DISPLAY 0.723404 (-675 170);
PAINT GREEN (-675 170);
DISPLAY INVISIBLE (-675 170);
FORCEPROP 2 LAST CDS_LIB pure_quanta
J 0
(-575 350);
DISPLAY INVISIBLE (-575 350);
FORCEPROP 0 LAST CDS_LOCATION X43
J 0
(-700 775);
DISPLAY 1.021277 (-700 775);
DISPLAY INVISIBLE (-700 775);
FORCEPROP 0 LAST $SEC 1
J 0
(-700 775);
DISPLAY 0.680851 (-700 775);
PAINT MONO (-700 775);
DISPLAY INVISIBLE (-700 775);
FORCEPROP 0 LAST CDS_SEC 1
J 0
(-700 775);
DISPLAY 1.021277 (-700 775);
DISPLAY INVISIBLE (-700 775);
FORCEADD QUANTA_TITLE_BLOCK_C..1
(6450 -1775);
FORCEPROP 0 LAST CDS_CON_LAST_MODIFIED Fri Aug 25 14:05:31 2023
J 0
(4565 -1760);
DISPLAY INVISIBLE (4565 -1760);
FORCEPROP 2 LAST CUSTOM_TXT_CDS <XR_PAGE_TITLE>
J 0
(-1440 3475);
DISPLAY 0.638298 (-1440 3475);
PAINT PINK (-1440 3475);
DISPLAY INVISIBLE (-1440 3475);
FORCEPROP 2 LAST CUSTOM_TXT_CDS <CON_LAST_MODIFIED>
J 0
(4565 -1760);
DISPLAY 0.978723 (4565 -1760);
FORCEPROP 2 LAST CUSTOM_TXT_CDS <Q_NUMBER>
J 0
(5047 -1672);
DISPLAY 1.212766 (5047 -1672);
FORCEPROP 2 LAST CUSTOM_TXT_CDS <NAME_1>
J 0
(3275 -1600);
FORCEPROP 2 LAST CUSTOM_TXT_CDS <NAME_2>
J 0
(3275 -1725);
FORCEPROP 2 LAST CUSTOM_TXT_CDS <Q_PROJ>
J 0
(4068 -1673);
DISPLAY 1.212766 (4068 -1673);
FORCEPROP 2 LAST CUSTOM_TXT_CDS <Q_REV>
J 0
(6266 -1672);
DISPLAY 1.212766 (6266 -1672);
FORCEPROP 2 LAST CUSTOM_TXT_CDS <CON_PAGE_NUM> OF <CON_TOTAL_PAGES>
J 0
(6004 -1757);
DISPLAY 0.978723 (6004 -1757);
FORCEPROP 1 LAST Q_TITLE TDR
J 0
(-2816 -1724);
DISPLAY 2.446809 (-2816 -1724);
PAINT GREEN (-2816 -1724);
FORCEPROP 1 LAST Q_DEPT 
J 1
(2687 -1726);
DISPLAY 1.957447 (2687 -1726);
PAINT GREEN (2687 -1726);
FORCEPROP 2 LAST CDS_LIB pure_quanta
J 0
(6450 -1775);
DISPLAY INVISIBLE (6450 -1775);
FORCEPROP 1 LAST CDS_LMAN_SYM_OUTLINE -9475,6775,100,-125
J 0
(6450 -1775);
DISPLAY 0.468085 (6450 -1775);
PAINT GREEN (6450 -1775);
DISPLAY INVISIBLE (6450 -1775);
FORCEPROP 1 LAST COMMENT_BODY TRUE
J 0
(6462 -1788);
DISPLAY 0.978723 (6462 -1788);
PAINT GREEN (6462 -1788);
DISPLAY INVISIBLE (6462 -1788);
FORCEPROP 2 LAST PAGE_BORDER TRUE
J 0
(-1440 3475);
DISPLAY 0.638298 (-1440 3475);
PAINT PINK (-1440 3475);
DISPLAY INVISIBLE (-1440 3475);
WIRE 16 -1 (-2325 -600)(-2325 -500);
WIRE 16 -1 (-2325 175)(-2325 275);
WIRE 16 -1 (-2325 850)(-2325 950);
WIRE 16 -1 (-2325 1625)(-2325 1725);
WIRE 16 -1 (-175 -600)(-175 -500);
WIRE 16 -1 (-175 175)(-175 275);
WIRE 16 -1 (-175 850)(-175 950);
WIRE 16 -1 (-175 1625)(-175 1725);
WIRE 16 -1 (-2325 2400)(-2325 2500);
WIRE 16 -1 (-2325 3175)(-2325 3275);
WIRE 16 -1 (-175 2400)(-175 2500);
WIRE 16 -1 (-175 3175)(-175 3275);
WIRE 16 -1 (-175 3425)(-300 3425);
WIRE 16 -1 (-300 3275)(-175 3275);
WIRE 16 -1 (-175 3275)(-175 3425);
WIRE 16 -1 (-300 2500)(-175 2500);
WIRE 16 -1 (-175 2500)(-175 2650);
WIRE 16 -1 (-175 2650)(-300 2650);
WIRE 16 -1 (-175 1875)(-300 1875);
WIRE 16 -1 (-300 1725)(-175 1725);
WIRE 16 -1 (-175 1725)(-175 1875);
WIRE 16 -1 (-850 1875)(-1625 1875);
WIRE 16 -1 (-850 2500)(-1625 2500);
WIRE 16 -1 (-850 1725)(-1625 1725);
WIRE 16 -1 (-850 2650)(-1625 2650);
WIRE 16 -1 (-850 3275)(-1625 3275);
WIRE 16 -1 (-850 3425)(-1625 3425);
WIRE 16 -1 (-2325 3275)(-2175 3275);
WIRE 16 -1 (-2325 3275)(-2325 3425);
WIRE 16 -1 (-2325 3425)(-2175 3425);
WIRE 16 -1 (-2325 2500)(-2175 2500);
WIRE 16 -1 (-2325 2500)(-2325 2650);
WIRE 16 -1 (-2325 2650)(-2175 2650);
WIRE 16 -1 (-2325 1725)(-2175 1725);
WIRE 16 -1 (-2325 1725)(-2325 1875);
WIRE 16 -1 (-2325 1875)(-2175 1875);
WIRE 16 -1 (-300 950)(-175 950);
WIRE 16 -1 (-175 950)(-175 1100);
WIRE 16 -1 (-175 1100)(-300 1100);
WIRE 16 -1 (-175 425)(-300 425);
WIRE 16 -1 (-300 275)(-175 275);
WIRE 16 -1 (-175 275)(-175 425);
WIRE 16 -1 (-175 -350)(-300 -350);
WIRE 16 -1 (-300 -500)(-175 -500);
WIRE 16 -1 (-175 -500)(-175 -350);
WIRE 16 -1 (-850 1100)(-1625 1100);
WIRE 16 -1 (-850 -350)(-1625 -350);
WIRE 16 -1 (-850 275)(-1625 275);
WIRE 16 -1 (-850 425)(-1625 425);
WIRE 16 -1 (-850 950)(-1625 950);
WIRE 16 -1 (-850 -500)(-1625 -500);
WIRE 16 -1 (-2325 950)(-2175 950);
WIRE 16 -1 (-2325 950)(-2325 1100);
WIRE 16 -1 (-2325 1100)(-2175 1100);
WIRE 16 -1 (-2325 275)(-2175 275);
WIRE 16 -1 (-2325 275)(-2325 425);
WIRE 16 -1 (-2325 425)(-2175 425);
WIRE 16 -1 (-2325 -500)(-2175 -500);
WIRE 16 -1 (-2325 -500)(-2325 -350);
WIRE 16 -1 (-2325 -350)(-2175 -350);
DOT 1 (-2325 -500);
DOT 1 (-2325 275);
DOT 1 (-2325 950);
DOT 1 (-175 -500);
DOT 1 (-175 275);
DOT 1 (-175 950);
DOT 1 (-2325 1725);
DOT 1 (-2325 2500);
DOT 1 (-2325 3275);
DOT 1 (-175 1725);
DOT 1 (-175 2500);
DOT 1 (-175 3275);
FORCENOTE
NECK 85 OHM
(-2025 4650) 0;
DISPLAY LEFT (-2025 4650);
DISPLAY 3.148936 (-2025 4650);
PAINT WHITE (-2025 4650);
FORCENOTE
20230116 ADD TDR FOR NECK
(200 4550) 0;
DISPLAY LEFT (200 4550);
DISPLAY 2.510638 (200 4550);
PAINT PINK (200 4550);
FORCENOTE
20230204 DEL X40,X48,X41,X33
(200 4375) 0;
DISPLAY LEFT (200 4375);
DISPLAY 2.510638 (200 4375);
PAINT PINK (200 4375);
QUIT
